(kicad_pcb
	(version 20241229)
	(generator "pcbnew")
	(generator_version "9.0")
	(general
		(thickness 1.552)
		(legacy_teardrops no)
	)
	(paper "A4")
	(title_block
		(date "2023-07-25")
		(rev "1.1.4")
		(comment 9 "footprints 53-57 of 379")
	)
	(layers
		(0 "F.Cu" signal)
		(4 "In1.Cu" signal)
		(6 "In2.Cu" signal)
		(8 "In3.Cu" signal)
		(10 "In4.Cu" signal)
		(12 "In5.Cu" signal)
		(14 "In6.Cu" signal)
		(2 "B.Cu" signal)
		(9 "F.Adhes" user "F.Adhesive")
		(11 "B.Adhes" user "B.Adhesive")
		(13 "F.Paste" user)
		(15 "B.Paste" user)
		(5 "F.SilkS" user "F.Silkscreen")
		(7 "B.SilkS" user "B.Silkscreen")
		(1 "F.Mask" user)
		(3 "B.Mask" user)
		(17 "Dwgs.User" user "User.Drawings")
		(19 "Cmts.User" user "User.Comments")
		(21 "Eco1.User" user "User.Eco1")
		(23 "Eco2.User" user "User.Eco2")
		(25 "Edge.Cuts" user)
		(27 "Margin" user)
		(31 "F.CrtYd" user "F.Courtyard")
		(29 "B.CrtYd" user "B.Courtyard")
		(35 "F.Fab" user)
		(33 "B.Fab" user)
	)
	(footprint "antmicro-footprints:R_0402_1005Metric"
		(layer "F.Cu")
		(at 142.215 117.85 180)
		(descr "Resistor SMD 0402")
		(tags "resistor SMD 0402")
		(property "Reference" "R33"
			(at 0.985 -1.49 180)
			(layer "F.SilkS")
			(effects
				(font
					(size 0.65 0.65)
					(thickness 0.15)
				)
				(justify left bottom)
			)
		)
		(property "Value" "R_12k_0402"
			(at 0 1.4 180)
			(layer "F.Fab")
			(hide yes)
			(effects
				(font
					(size 0.7 0.7)
					(thickness 0.15)
				)
				(justify left bottom)
			)
		)
		(property "Datasheet" "https://www.bourns.com/docs/product-datasheets/cr.pdf"
			(at 0 0 180)
			(layer "F.Fab")
			(hide yes)
			(effects
				(font
					(size 1.27 1.27)
					(thickness 0.15)
				)
			)
		)
		(property "Description" "SMD Chip Resistor, 12 kohm, ± 1%, 62.5 mW, 0402 [1005 Metric], Thick Film, General Purpose"
			(at 0 0 180)
			(layer "F.Fab")
			(hide yes)
			(effects
				(font
					(size 1.27 1.27)
					(thickness 0.15)
				)
			)
		)
		(property "Author" "Antmicro"
			(at 284.43 235.7 0)
			(layer "F.Fab")
			(hide yes)
			(effects
				(font
					(size 1 1)
					(thickness 0.15)
				)
			)
		)
		(property "License" "Apache-2.0"
			(at 284.43 235.7 0)
			(layer "F.Fab")
			(hide yes)
			(effects
				(font
					(size 1 1)
					(thickness 0.15)
				)
			)
		)
		(property "MPN" "CR0402-FX-1202GLF"
			(at 284.43 235.7 0)
			(layer "F.Fab")
			(hide yes)
			(effects
				(font
					(size 1 1)
					(thickness 0.15)
				)
			)
		)
		(property "Manufacturer" "Bourns"
			(at 284.43 235.7 0)
			(layer "F.Fab")
			(hide yes)
			(effects
				(font
					(size 1 1)
					(thickness 0.15)
				)
			)
		)
		(property "Tolerance" "1%"
			(at 284.43 235.7 0)
			(layer "F.Fab")
			(hide yes)
			(effects
				(font
					(size 1 1)
					(thickness 0.15)
				)
			)
		)
		(property "Val" "12k"
			(at 284.43 235.7 0)
			(layer "F.Fab")
			(hide yes)
			(effects
				(font
					(size 1 1)
					(thickness 0.15)
				)
			)
		)
		(sheetname "/Power Supply/")
		(sheetfile "supply.kicad_sch")
		(attr smd)
		(fp_rect
			(start -0.925 -0.47)
			(end 0.925 0.47)
			(stroke
				(width 0.05)
				(type default)
			)
			(fill no)
			(layer "F.CrtYd")
		)
		(fp_rect
			(start -0.5 -0.25)
			(end 0.5 0.25)
			(stroke
				(width 0.15)
				(type solid)
			)
			(fill no)
			(layer "F.Fab")
		)
		(fp_text user "${REFERENCE}"
			(at -0.95 3.168 180)
			(layer "F.Fab")
			(effects
				(font
					(size 0.7 0.7)
					(thickness 0.15)
				)
				(justify left bottom)
			)
		)
		(fp_text user "Author: Antmicro"
			(at -0.95 4.169 180)
			(layer "F.Fab")
			(effects
				(font
					(size 0.7 0.7)
					(thickness 0.15)
				)
				(justify left bottom)
			)
		)
		(fp_text user "License: Apache-2.0"
			(at -0.95 5.169 180)
			(layer "F.Fab")
			(effects
				(font
					(size 0.7 0.7)
					(thickness 0.15)
				)
				(justify left bottom)
			)
		)
		(pad "1" smd roundrect
			(at -0.48 0 180)
			(size 0.59 0.64)
			(layers "F.Cu" "F.Mask" "F.Paste")
			(roundrect_rratio 0.25)
			(net 282 "Net-(U9-ADJ)")
			(pintype "passive")
		)
		(pad "2" smd roundrect
			(at 0.48 0 180)
			(size 0.59 0.64)
			(layers "F.Cu" "F.Mask" "F.Paste")
			(roundrect_rratio 0.25)
			(net 279 "Net-(U9-V_{OUT})")
			(pintype "passive")
		)
	)
	(footprint "antmicro-footprints:Oscillator_SMD_YIC_OSC-S5_5x3.2mm"
		(layer "F.Cu")
		(at 113.14 89.25)
		(property "Reference" "Y2"
			(at -2.11 3.61 90)
			(unlocked yes)
			(layer "F.SilkS")
			(effects
				(font
					(size 0.65 0.65)
					(thickness 0.15)
				)
				(justify left bottom)
			)
		)
		(property "Value" "Oscillator_SMD_40MHz_OSC-S5"
			(at 0 3 0)
			(unlocked yes)
			(layer "F.Fab")
			(hide yes)
			(effects
				(font
					(size 0.7 0.7)
					(thickness 0.15)
				)
				(justify left bottom)
			)
		)
		(property "Datasheet" "https://www.tme.eu/Document/456c7b2975a812de7905406dd4f750d9/YIC-S5.pdf"
			(at 0 0 0)
			(layer "F.Fab")
			(hide yes)
			(effects
				(font
					(size 1.27 1.27)
					(thickness 0.15)
				)
			)
		)
		(property "Description" "Generator: quartz, 40MHz, SMD, 3.3V, ±50ppm, -20÷70°C, 5x3.2x1.3mm"
			(at 0 0 0)
			(layer "F.Fab")
			(hide yes)
			(effects
				(font
					(size 1.27 1.27)
					(thickness 0.15)
				)
			)
		)
		(property "Author" "Antmicro"
			(at 23.89 202.39 90)
			(layer "F.Fab")
			(hide yes)
			(effects
				(font
					(size 1 1)
					(thickness 0.15)
				)
			)
		)
		(property "License" "Apache-2.0"
			(at 23.89 202.39 90)
			(layer "F.Fab")
			(hide yes)
			(effects
				(font
					(size 1 1)
					(thickness 0.15)
				)
			)
		)
		(property "MPN" "OSC40M-3.3/S5"
			(at 23.89 202.39 90)
			(layer "F.Fab")
			(hide yes)
			(effects
				(font
					(size 1 1)
					(thickness 0.15)
				)
			)
		)
		(property "Manufacturer" "YIC"
			(at 23.89 202.39 90)
			(layer "F.Fab")
			(hide yes)
			(effects
				(font
					(size 1 1)
					(thickness 0.15)
				)
			)
		)
		(property "Val" "40 MHz"
			(at 0 0 0)
			(unlocked yes)
			(layer "F.Fab")
			(hide yes)
			(effects
				(font
					(size 1 1)
					(thickness 0.15)
				)
			)
		)
		(sheetname "/FPGA/")
		(sheetfile "fpga.kicad_sch")
		(attr smd)
		(fp_line
			(start -1.899 2.618)
			(end -1.899 1.618)
			(stroke
				(width 0.15)
				(type solid)
			)
			(layer "F.SilkS")
		)
		(fp_line
			(start -1.899 2.618)
			(end -0.901 2.618)
			(stroke
				(width 0.15)
				(type solid)
			)
			(layer "F.SilkS")
		)
		(fp_line
			(start -1.88 -2.65)
			(end -1.88 -1.651)
			(stroke
				(width 0.15)
				(type solid)
			)
			(layer "F.SilkS")
		)
		(fp_line
			(start -1.88 -2.65)
			(end -0.881 -2.65)
			(stroke
				(width 0.15)
				(type solid)
			)
			(layer "F.SilkS")
		)
		(fp_line
			(start 1.9 -2.68)
			(end 0.901 -2.68)
			(stroke
				(width 0.15)
				(type solid)
			)
			(layer "F.SilkS")
		)
		(fp_line
			(start 1.9 -2.68)
			(end 1.9 -1.681)
			(stroke
				(width 0.15)
				(type solid)
			)
			(layer "F.SilkS")
		)
		(fp_line
			(start 1.9 2.618)
			(end 0.901 2.618)
			(stroke
				(width 0.15)
				(type solid)
			)
			(layer "F.SilkS")
		)
		(fp_line
			(start 1.9 2.618)
			(end 1.9 1.618)
			(stroke
				(width 0.15)
				(type solid)
			)
			(layer "F.SilkS")
		)
		(fp_circle
			(center -1.96 -1.34)
			(end -1.96 -1.29)
			(stroke
				(width 0.15)
				(type solid)
			)
			(fill yes)
			(layer "F.SilkS")
		)
		(fp_rect
			(start 2.1 -3.03)
			(end -2.101 2.969)
			(stroke
				(width 0.05)
				(type solid)
			)
			(fill no)
			(layer "F.CrtYd")
		)
		(fp_rect
			(start 1.749 -2.53)
			(end -1.75 2.469)
			(stroke
				(width 0.15)
				(type solid)
			)
			(fill no)
			(layer "F.Fab")
		)
		(fp_text user "${REFERENCE}"
			(at -3 6.999 0)
			(unlocked yes)
			(layer "F.Fab")
			(effects
				(font
					(size 0.7 0.7)
					(thickness 0.15)
				)
				(justify left bottom)
			)
		)
		(fp_text user "Author: Antmicro"
			(at -3 8.198 0)
			(layer "F.Fab")
			(effects
				(font
					(size 0.7 0.7)
					(thickness 0.15)
				)
				(justify left bottom)
			)
		)
		(fp_text user "License: Apache-2.0"
			(at -3 9.399 0)
			(layer "F.Fab")
			(effects
				(font
					(size 0.7 0.7)
					(thickness 0.15)
				)
				(justify left bottom)
			)
		)
		(pad "1" smd roundrect
			(at -1.101 -1.3 270)
			(size 1.6 1.4)
			(layers "F.Cu" "F.Mask" "F.Paste")
			(roundrect_rratio 0.2)
			(net 286 "Net-(Y2-EN)")
			(pinfunction "EN")
			(pintype "input")
		)
		(pad "2" smd roundrect
			(at -1.101 1.3 270)
			(size 1.6 1.4)
			(layers "F.Cu" "F.Mask" "F.Paste")
			(roundrect_rratio 0.2)
			(net 1 "GND")
			(pinfunction "GND")
			(pintype "power_in")
		)
		(pad "3" smd roundrect
			(at 1.1 1.3 270)
			(size 1.6 1.4)
			(layers "F.Cu" "F.Mask" "F.Paste")
			(roundrect_rratio 0.2)
			(net 186 "40MHz_3V3")
			(pinfunction "OUT")
			(pintype "output")
		)
		(pad "4" smd roundrect
			(at 1.1 -1.3 270)
			(size 1.6 1.4)
			(layers "F.Cu" "F.Mask" "F.Paste")
			(roundrect_rratio 0.2)
			(net 2 "+3V3")
			(pinfunction "VDD")
			(pintype "power_in")
		)
	)
	(footprint "antmicro-footprints:TP_SMD_0.75mm"
		(layer "F.Cu")
		(at 150.33 71.7 90)
		(property "Reference" "TP4"
			(at -0.64 1.4 90)
			(layer "F.SilkS")
			(effects
				(font
					(size 0.65 0.65)
					(thickness 0.15)
				)
				(justify left bottom)
			)
		)
		(property "Value" "TP_0.75mm_SMD"
			(at 0 1.2 90)
			(layer "F.Fab")
			(hide yes)
			(effects
				(font
					(size 0.7 0.7)
					(thickness 0.15)
				)
				(justify left bottom)
			)
		)
		(property "Description" "SMT test point"
			(at 0 0 90)
			(layer "F.Fab")
			(hide yes)
			(effects
				(font
					(size 1.27 1.27)
					(thickness 0.15)
				)
			)
		)
		(property "Author" "Antmicro"
			(at 222.03 -78.63 0)
			(layer "F.Fab")
			(hide yes)
			(effects
				(font
					(size 1 1)
					(thickness 0.15)
				)
			)
		)
		(property "License" "Apache-2.0"
			(at 222.03 -78.63 0)
			(layer "F.Fab")
			(hide yes)
			(effects
				(font
					(size 1 1)
					(thickness 0.15)
				)
			)
		)
		(property "MPN" ""
			(at 222.03 -78.63 0)
			(layer "F.Fab")
			(hide yes)
			(effects
				(font
					(size 1 1)
					(thickness 0.15)
				)
			)
		)
		(property "Manufacturer" ""
			(at 222.03 -78.63 0)
			(layer "F.Fab")
			(hide yes)
			(effects
				(font
					(size 1 1)
					(thickness 0.15)
				)
			)
		)
		(sheetname "/Power Supply/")
		(sheetfile "supply.kicad_sch")
		(attr exclude_from_pos_files)
		(fp_circle
			(center 0 0)
			(end 0.475 0)
			(stroke
				(width 0.05)
				(type default)
			)
			(fill no)
			(layer "F.CrtYd")
		)
		(fp_text user "${REFERENCE}"
			(at -0.4 2.7 90)
			(layer "F.Fab")
			(effects
				(font
					(size 0.7 0.7)
					(thickness 0.15)
				)
				(justify left bottom)
			)
		)
		(fp_text user "Author: Antmicro"
			(at -0.4 3.901 90)
			(layer "F.Fab")
			(effects
				(font
					(size 0.7 0.7)
					(thickness 0.15)
				)
				(justify left bottom)
			)
		)
		(fp_text user "License: Apache-2.0"
			(at -0.4 5.101 90)
			(layer "F.Fab")
			(effects
				(font
					(size 0.7 0.7)
					(thickness 0.15)
				)
				(justify left bottom)
			)
		)
		(pad "1" smd circle
			(at 0 0 90)
			(size 0.75 0.75)
			(layers "F.Cu" "F.Mask")
			(net 4 "1V0_Power")
			(pinfunction "1")
			(pintype "passive")
		)
	)
	(footprint "antmicro-footprints:R_0402_1005Metric"
		(layer "F.Cu")
		(at 144.39 106.35 90)
		(descr "Resistor SMD 0402")
		(tags "resistor SMD 0402")
		(property "Reference" "R24"
			(at 0.81 0.44 90)
			(layer "F.SilkS")
			(effects
				(font
					(size 0.65 0.65)
					(thickness 0.15)
				)
				(justify left bottom)
			)
		)
		(property "Value" "R_0R_0402"
			(at 0 1.4 90)
			(layer "F.Fab")
			(hide yes)
			(effects
				(font
					(size 0.7 0.7)
					(thickness 0.15)
				)
				(justify left bottom)
			)
		)
		(property "Datasheet" "https://industrial.panasonic.com/cdbs/www-data/pdf/RDA0000/AOA0000C301.pdf"
			(at 0 0 90)
			(layer "F.Fab")
			(hide yes)
			(effects
				(font
					(size 1.27 1.27)
					(thickness 0.15)
				)
			)
		)
		(property "Description" "SMD Chip Resistor, Jumper, 0 ohm, 100 mW, 0402 [1005 Metric], Thick Film, General Purpose"
			(at 0 0 90)
			(layer "F.Fab")
			(hide yes)
			(effects
				(font
					(size 1.27 1.27)
					(thickness 0.15)
				)
			)
		)
		(property "Author" "Antmicro"
			(at 250.74 -38.04 0)
			(layer "F.Fab")
			(hide yes)
			(effects
				(font
					(size 1 1)
					(thickness 0.15)
				)
			)
		)
		(property "Current" "1A"
			(at 250.74 -38.04 0)
			(layer "F.Fab")
			(hide yes)
			(effects
				(font
					(size 1 1)
					(thickness 0.15)
				)
			)
		)
		(property "License" "Apache-2.0"
			(at 250.74 -38.04 0)
			(layer "F.Fab")
			(hide yes)
			(effects
				(font
					(size 1 1)
					(thickness 0.15)
				)
			)
		)
		(property "MPN" "ERJ2GE0R00X"
			(at 250.74 -38.04 0)
			(layer "F.Fab")
			(hide yes)
			(effects
				(font
					(size 1 1)
					(thickness 0.15)
				)
			)
		)
		(property "Manufacturer" "Panasonic"
			(at 250.74 -38.04 0)
			(layer "F.Fab")
			(hide yes)
			(effects
				(font
					(size 1 1)
					(thickness 0.15)
				)
			)
		)
		(property "Tolerance" "~"
			(at 250.74 -38.04 0)
			(layer "F.Fab")
			(hide yes)
			(effects
				(font
					(size 1 1)
					(thickness 0.15)
				)
			)
		)
		(property "Val" "0R"
			(at 250.74 -38.04 0)
			(layer "F.Fab")
			(hide yes)
			(effects
				(font
					(size 1 1)
					(thickness 0.15)
				)
			)
		)
		(sheetname "/Power Supply/")
		(sheetfile "supply.kicad_sch")
		(attr smd)
		(fp_rect
			(start -0.925 -0.47)
			(end 0.925 0.47)
			(stroke
				(width 0.05)
				(type default)
			)
			(fill no)
			(layer "F.CrtYd")
		)
		(fp_rect
			(start -0.5 -0.25)
			(end 0.5 0.25)
			(stroke
				(width 0.15)
				(type solid)
			)
			(fill no)
			(layer "F.Fab")
		)
		(fp_text user "Author: Antmicro"
			(at -0.95 4.169 90)
			(layer "F.Fab")
			(effects
				(font
					(size 0.7 0.7)
					(thickness 0.15)
				)
				(justify left bottom)
			)
		)
		(fp_text user "${REFERENCE}"
			(at -0.95 3.168 90)
			(layer "F.Fab")
			(effects
				(font
					(size 0.7 0.7)
					(thickness 0.15)
				)
				(justify left bottom)
			)
		)
		(fp_text user "License: Apache-2.0"
			(at -0.95 5.169 90)
			(layer "F.Fab")
			(effects
				(font
					(size 0.7 0.7)
					(thickness 0.15)
				)
				(justify left bottom)
			)
		)
		(pad "1" smd roundrect
			(at -0.48 0 90)
			(size 0.59 0.64)
			(layers "F.Cu" "F.Mask" "F.Paste")
			(roundrect_rratio 0.25)
			(net 264 "Net-(U8-V_{IN})")
			(pintype "passive")
		)
		(pad "2" smd roundrect
			(at 0.48 0 90)
			(size 0.59 0.64)
			(layers "F.Cu" "F.Mask" "F.Paste")
			(roundrect_rratio 0.25)
			(net 268 "Net-(U8-EN)")
			(pintype "passive")
		)
	)
	(footprint "antmicro-footprints:R_0603_1608Metric"
		(layer "F.Cu")
		(at 169.83 82.55 180)
		(descr "Resistor SMD 0603")
		(tags "resistor SMD 0603")
		(property "Reference" "R103"
			(at 4.1 -0.39 180)
			(layer "F.SilkS")
			(effects
				(font
					(size 0.65 0.65)
					(thickness 0.15)
				)
				(justify left bottom)
			)
		)
		(property "Value" "R_470R_0603"
			(at 0 1.6 180)
			(layer "F.Fab")
			(hide yes)
			(effects
				(font
					(size 0.7 0.7)
					(thickness 0.15)
				)
				(justify left bottom)
			)
		)
		(property "Datasheet" "https://www.bourns.com/docs/product-datasheets/cr.pdf"
			(at 0 0 180)
			(layer "F.Fab")
			(hide yes)
			(effects
				(font
					(size 1.27 1.27)
					(thickness 0.15)
				)
			)
		)
		(property "Description" "SMD Chip Resistor, 470 ohm, ± 1%, 100 mW, 0603 [1608 Metric], Thick Film, General Purpose"
			(at 0 0 180)
			(layer "F.Fab")
			(hide yes)
			(effects
				(font
					(size 1.27 1.27)
					(thickness 0.15)
				)
			)
		)
		(property "Author" "Antmicro"
			(at 339.66 165.1 0)
			(layer "F.Fab")
			(hide yes)
			(effects
				(font
					(size 1 1)
					(thickness 0.15)
				)
			)
		)
		(property "License" "Apache-2.0"
			(at 339.66 165.1 0)
			(layer "F.Fab")
			(hide yes)
			(effects
				(font
					(size 1 1)
					(thickness 0.15)
				)
			)
		)
		(property "MPN" "CR0603-FX-4700ELF"
			(at 339.66 165.1 0)
			(layer "F.Fab")
			(hide yes)
			(effects
				(font
					(size 1 1)
					(thickness 0.15)
				)
			)
		)
		(property "Manufacturer" "Bourns"
			(at 339.66 165.1 0)
			(layer "F.Fab")
			(hide yes)
			(effects
				(font
					(size 1 1)
					(thickness 0.15)
				)
			)
		)
		(property "Tolerance" "1%"
			(at 339.66 165.1 0)
			(layer "F.Fab")
			(hide yes)
			(effects
				(font
					(size 1 1)
					(thickness 0.15)
				)
			)
		)
		(property "Val" "470R"
			(at 339.66 165.1 0)
			(layer "F.Fab")
			(hide yes)
			(effects
				(font
					(size 1 1)
					(thickness 0.15)
				)
			)
		)
		(sheetname "/Peripherals/")
		(sheetfile "peripherals.kicad_sch")
		(attr smd)
		(fp_line
			(start -0.15 0.4)
			(end 0.15 0.4)
			(stroke
				(width 0.15)
				(type solid)
			)
			(layer "F.SilkS")
		)
		(fp_line
			(start -0.15 -0.4)
			(end 0.15 -0.4)
			(stroke
				(width 0.15)
				(type solid)
			)
			(layer "F.SilkS")
		)
		(fp_rect
			(start -1.25 -0.65)
			(end 1.25 0.65)
			(stroke
				(width 0.05)
				(type solid)
			)
			(fill no)
			(layer "F.CrtYd")
		)
		(fp_rect
			(start -0.8 -0.4)
			(end 0.8 0.4)
			(stroke
				(width 0.15)
				(type solid)
			)
			(fill no)
			(layer "F.Fab")
		)
		(fp_text user "${REFERENCE}"
			(at -1.25 3.898 180)
			(layer "F.Fab")
			(effects
				(font
					(size 0.7 0.7)
					(thickness 0.15)
				)
				(justify left bottom)
			)
		)
		(fp_text user "Author: Antmicro"
			(at -1.25 4.9 180)
			(layer "F.Fab")
			(effects
				(font
					(size 0.7 0.7)
					(thickness 0.15)
				)
				(justify left bottom)
			)
		)
		(fp_text user "License: Apache-2.0"
			(at -1.25 5.9 180)
			(layer "F.Fab")
			(effects
				(font
					(size 0.7 0.7)
					(thickness 0.15)
				)
				(justify left bottom)
			)
		)
		(pad "1" smd roundrect
			(at -0.7 0 180)
			(size 0.8 1)
			(layers "F.Cu" "F.Mask" "F.Paste")
			(roundrect_rratio 0.2)
			(net 256 "Net-(D10-A)")
			(pintype "passive")
		)
		(pad "2" smd roundrect
			(at 0.7 0 180)
			(size 0.8 1)
			(layers "F.Cu" "F.Mask" "F.Paste")
			(roundrect_rratio 0.2)
			(net 16 "/Peripherals/FFC1_5V")
			(pintype "passive")
		)
	)
)
